(kicad_pcb
	(version 20260206)
	(generator "pcbnew")
	(generator_version "10.0")
	(general
		(thickness 1.6)
		(legacy_teardrops no)
	)
	(paper "A4")
	(title_block
		(title "01162023_DA0F0TEBIF0_F0T_Expander_BD_F_brd_V02_OCP.brd")
		(comment 1 "Grand Teton / footprints 7688-7695 of 9728")
	)
	(layers
		(0 "F.Cu" signal "TOP")
		(4 "In1.Cu" signal "GND")
		(6 "In2.Cu" signal "VCC")
		(8 "In3.Cu" signal "VCC1")
		(10 "In4.Cu" signal "GND1")
		(12 "In5.Cu" signal "IN1")
		(14 "In6.Cu" signal "GND2")
		(16 "In7.Cu" signal "IN2")
		(18 "In8.Cu" signal "GND3")
		(20 "In9.Cu" signal "IN3")
		(22 "In10.Cu" signal "GND4")
		(24 "In11.Cu" signal "IN4")
		(26 "In12.Cu" signal "GND5")
		(28 "In13.Cu" signal "IN5")
		(30 "In14.Cu" signal "GND6")
		(32 "In15.Cu" signal "IN6")
		(34 "In16.Cu" signal "GND7")
		(2 "B.Cu" signal "BOTTOM")
		(9 "F.Adhes" user "F.Adhesive")
		(11 "B.Adhes" user "B.Adhesive")
		(13 "F.Paste" user "Package Geometry/Pastemask Top")
		(15 "B.Paste" user "Package Geometry/Pastemask Bottom")
		(5 "F.SilkS" user "Ref Des/Silkscreen Top")
		(7 "B.SilkS" user "Ref Des/Silkscreen Bottom")
		(1 "F.Mask" user "Board Geometry/Soldermask Top")
		(3 "B.Mask" user "Board Geometry/Soldermask Bottom")
		(17 "Dwgs.User" user "User.Drawings")
		(19 "Cmts.User" user "User.Comments")
		(21 "Eco1.User" user "User.Eco1")
		(23 "Eco2.User" user "User.Eco2")
		(25 "Edge.Cuts" user "Board Geometry/Outline")
		(27 "Margin" user)
		(31 "F.CrtYd" user "Package Geometry/Place Bound Top")
		(29 "B.CrtYd" user "Package Geometry/Place Bound Bottom")
		(35 "F.Fab" user "Ref Des/Assembly Top")
		(33 "B.Fab" user "Ref Des/Assembly Bottom")
	)
	(footprint ""
		(layer "B.Cu")
		(at 256.351532 -84.604352 180)
		(property "Reference" "C2651"
			(at 0 0 0)
			(layer "B.SilkS")
			(hide yes)
			(effects
				(font
					(size 1.27 1.27)
				)
				(justify mirror)
			)
		)
		(property "Value" ""
			(at 0 0 0)
			(layer "B.Fab")
			(effects
				(font
					(size 1.27 1.27)
				)
				(justify mirror)
			)
		)
		(duplicate_pad_numbers_are_jumpers no)
		(fp_line
			(start 0.7874 0.4064)
			(end 0.7874 -0.4064)
			(stroke
				(width 0.1524)
				(type default)
			)
			(layer "B.SilkS")
		)
		(fp_line
			(start 0.7874 -0.4064)
			(end -0.7874 -0.4064)
			(stroke
				(width 0.1524)
				(type default)
			)
			(layer "B.SilkS")
		)
		(fp_line
			(start -0.7874 0.4064)
			(end 0.7874 0.4064)
			(stroke
				(width 0.1524)
				(type default)
			)
			(layer "B.SilkS")
		)
		(fp_line
			(start -0.7874 -0.4064)
			(end -0.7874 0.4064)
			(stroke
				(width 0.1524)
				(type default)
			)
			(layer "B.SilkS")
		)
		(fp_line
			(start 0.67945 0.3048)
			(end 0.67945 -0.305054)
			(stroke
				(width 0.1)
				(type default)
			)
			(layer "B.Fab")
		)
		(fp_line
			(start 0.67945 -0.305054)
			(end 0.12065 -0.305054)
			(stroke
				(width 0.1)
				(type default)
			)
			(layer "B.Fab")
		)
		(fp_line
			(start 0.12065 0.3048)
			(end 0.67945 0.3048)
			(stroke
				(width 0.1)
				(type default)
			)
			(layer "B.Fab")
		)
		(fp_line
			(start 0.12065 0.2794)
			(end 0.12065 0.3048)
			(stroke
				(width 0.1)
				(type default)
			)
			(layer "B.Fab")
		)
		(fp_line
			(start 0.12065 -0.2794)
			(end -0.12065 -0.2794)
			(stroke
				(width 0.1)
				(type default)
			)
			(layer "B.Fab")
		)
		(fp_line
			(start 0.12065 -0.305054)
			(end 0.12065 -0.2794)
			(stroke
				(width 0.1)
				(type default)
			)
			(layer "B.Fab")
		)
		(fp_line
			(start -0.120396 0.3048)
			(end -0.120396 0.2794)
			(stroke
				(width 0.1)
				(type default)
			)
			(layer "B.Fab")
		)
		(fp_line
			(start -0.120396 0.2794)
			(end 0.12065 0.2794)
			(stroke
				(width 0.1)
				(type default)
			)
			(layer "B.Fab")
		)
		(fp_line
			(start -0.12065 -0.2794)
			(end -0.12065 -0.3048)
			(stroke
				(width 0.1)
				(type default)
			)
			(layer "B.Fab")
		)
		(fp_line
			(start -0.12065 -0.3048)
			(end -0.67945 -0.3048)
			(stroke
				(width 0.1)
				(type default)
			)
			(layer "B.Fab")
		)
		(fp_line
			(start -0.67945 0.3048)
			(end -0.120396 0.3048)
			(stroke
				(width 0.1)
				(type default)
			)
			(layer "B.Fab")
		)
		(fp_line
			(start -0.67945 -0.3048)
			(end -0.67945 0.3048)
			(stroke
				(width 0.1)
				(type default)
			)
			(layer "B.Fab")
		)
		(pad "1" smd circle
			(at 0.40005 0)
			(size 0 0)
			(layers "B.Cu" "B.Mask" "B.Paste")
			(net "P3V3_CLK_GEN_VDDPT_CK440")
		)
		(pad "2" smd circle
			(at -0.40005 0)
			(size 0 0)
			(layers "B.Cu" "B.Mask" "B.Paste")
			(net "GND")
		)
	)
	(footprint ""
		(layer "B.Cu")
		(at 298.499784 -288.299906 90)
		(property "Reference" "C3270"
			(at 0 0 90)
			(layer "B.SilkS")
			(hide yes)
			(effects
				(font
					(size 1.27 1.27)
				)
				(justify mirror)
			)
		)
		(property "Value" ""
			(at 0 0 90)
			(layer "B.Fab")
			(effects
				(font
					(size 1.27 1.27)
				)
				(justify mirror)
			)
		)
		(duplicate_pad_numbers_are_jumpers no)
		(fp_line
			(start 0.299974 -0.150114)
			(end -0.299974 -0.150114)
			(stroke
				(width 0.1)
				(type default)
			)
			(layer "B.Fab")
		)
		(fp_line
			(start -0.299974 -0.150114)
			(end -0.299974 0.150114)
			(stroke
				(width 0.1)
				(type default)
			)
			(layer "B.Fab")
		)
		(fp_line
			(start 0.299974 0.150114)
			(end 0.299974 -0.150114)
			(stroke
				(width 0.1)
				(type default)
			)
			(layer "B.Fab")
		)
		(fp_line
			(start -0.299974 0.150114)
			(end 0.299974 0.150114)
			(stroke
				(width 0.1)
				(type default)
			)
			(layer "B.Fab")
		)
		(pad "1" smd rect
			(at 0.2667 0 270)
			(size 0.3048 0.381)
			(layers "B.Cu" "B.Mask" "B.Paste")
			(net "P1V25_PEX2")
		)
		(pad "2" smd rect
			(at -0.2667 0 270)
			(size 0.3048 0.381)
			(layers "B.Cu" "B.Mask" "B.Paste")
			(net "GND")
		)
	)
	(footprint ""
		(layer "B.Cu")
		(at 130.168904 -293.660068 90)
		(property "Reference" "PC104"
			(at 0 0 90)
			(layer "B.SilkS")
			(hide yes)
			(effects
				(font
					(size 1.27 1.27)
				)
				(justify mirror)
			)
		)
		(property "Value" ""
			(at 0 0 90)
			(layer "B.Fab")
			(effects
				(font
					(size 1.27 1.27)
				)
				(justify mirror)
			)
		)
		(duplicate_pad_numbers_are_jumpers no)
		(fp_line
			(start 4.84378 -2.150618)
			(end 4.53898 -2.150618)
			(stroke
				(width 0.1524)
				(type default)
			)
			(layer "B.SilkS")
		)
		(fp_line
			(start 4.84378 -2.150618)
			(end 4.842256 2.163064)
			(stroke
				(width 0.1524)
				(type default)
			)
			(layer "B.SilkS")
		)
		(fp_line
			(start 4.69138 -2.150618)
			(end 4.692396 2.161032)
			(stroke
				(width 0.1524)
				(type default)
			)
			(layer "B.SilkS")
		)
		(fp_line
			(start 4.53898 -2.150618)
			(end 4.539742 2.152142)
			(stroke
				(width 0.1524)
				(type default)
			)
			(layer "B.SilkS")
		)
		(fp_line
			(start 4.53898 -2.15011)
			(end -4.53898 -2.15011)
			(stroke
				(width 0.1524)
				(type default)
			)
			(layer "B.SilkS")
		)
		(fp_line
			(start -4.53898 -2.15011)
			(end -4.53898 2.15011)
			(stroke
				(width 0.1524)
				(type default)
			)
			(layer "B.SilkS")
		)
		(fp_line
			(start 4.53898 2.15011)
			(end 4.53898 -2.15011)
			(stroke
				(width 0.1524)
				(type default)
			)
			(layer "B.SilkS")
		)
		(fp_line
			(start -4.53898 2.15011)
			(end 4.53898 2.15011)
			(stroke
				(width 0.1524)
				(type default)
			)
			(layer "B.SilkS")
		)
		(fp_line
			(start 4.83108 2.150364)
			(end 4.447794 2.149348)
			(stroke
				(width 0.1524)
				(type default)
			)
			(layer "B.SilkS")
		)
		(fp_line
			(start 3.64998 -2.15011)
			(end -3.64998 -2.15011)
			(stroke
				(width 0.1)
				(type default)
			)
			(layer "B.Fab")
		)
		(fp_line
			(start -3.64998 -2.15011)
			(end -3.64998 2.15011)
			(stroke
				(width 0.1)
				(type default)
			)
			(layer "B.Fab")
		)
		(fp_line
			(start 3.64998 2.15011)
			(end 3.64998 -2.15011)
			(stroke
				(width 0.1)
				(type default)
			)
			(layer "B.Fab")
		)
		(fp_line
			(start -3.64998 2.15011)
			(end 3.64998 2.15011)
			(stroke
				(width 0.1)
				(type default)
			)
			(layer "B.Fab")
		)
		(fp_text user "+"
			(at 6.214872 -0.337058 90)
			(unlocked yes)
			(layer "B.SilkS")
			(effects
				(font
					(size 1.905 1.4224)
					(thickness 0.1524)
				)
				(justify left mirror)
			)
		)
		(fp_text user "-"
			(at -4.313174 -0.094488 90)
			(unlocked yes)
			(layer "B.SilkS")
			(effects
				(font
					(size 1.905 1.4224)
					(thickness 0.1524)
				)
				(justify left mirror)
			)
		)
		(fp_text user "+"
			(at 6.214872 -0.337058 90)
			(unlocked yes)
			(layer "B.Fab")
			(effects
				(font
					(size 1.905 1.4224)
					(thickness 0.1524)
				)
				(justify left mirror)
			)
		)
		(fp_text user "-"
			(at -4.313174 -0.094488 90)
			(unlocked yes)
			(layer "B.Fab")
			(effects
				(font
					(size 1.905 1.4224)
					(thickness 0.1524)
				)
				(justify left mirror)
			)
		)
		(pad "1" smd rect
			(at 3.199892 0 270)
			(size 2.413 2.8194)
			(layers "B.Cu" "B.Mask" "B.Paste")
			(net "P0V8_PEX1")
		)
		(pad "2" smd rect
			(at -3.199892 0 270)
			(size 2.413 2.8194)
			(layers "B.Cu" "B.Mask" "B.Paste")
			(net "GND")
		)
	)
	(footprint ""
		(layer "B.Cu")
		(at 104.178608 -357.366062 -90)
		(property "Reference" "C4178"
			(at 0 0 90)
			(layer "B.SilkS")
			(hide yes)
			(effects
				(font
					(size 1.27 1.27)
				)
				(justify mirror)
			)
		)
		(property "Value" ""
			(at 0 0 90)
			(layer "B.Fab")
			(effects
				(font
					(size 1.27 1.27)
				)
				(justify mirror)
			)
		)
		(duplicate_pad_numbers_are_jumpers no)
		(fp_line
			(start -0.7874 0.4064)
			(end 0.7874 0.4064)
			(stroke
				(width 0.1524)
				(type default)
			)
			(layer "B.SilkS")
		)
		(fp_line
			(start 0.7874 0.4064)
			(end 0.7874 -0.4064)
			(stroke
				(width 0.1524)
				(type default)
			)
			(layer "B.SilkS")
		)
		(fp_line
			(start -0.7874 -0.4064)
			(end -0.7874 0.4064)
			(stroke
				(width 0.1524)
				(type default)
			)
			(layer "B.SilkS")
		)
		(fp_line
			(start 0.7874 -0.4064)
			(end -0.7874 -0.4064)
			(stroke
				(width 0.1524)
				(type default)
			)
			(layer "B.SilkS")
		)
		(fp_line
			(start -0.67945 0.3048)
			(end -0.120396 0.3048)
			(stroke
				(width 0.1)
				(type default)
			)
			(layer "B.Fab")
		)
		(fp_line
			(start -0.120396 0.3048)
			(end -0.120396 0.2794)
			(stroke
				(width 0.1)
				(type default)
			)
			(layer "B.Fab")
		)
		(fp_line
			(start 0.12065 0.3048)
			(end 0.67945 0.3048)
			(stroke
				(width 0.1)
				(type default)
			)
			(layer "B.Fab")
		)
		(fp_line
			(start 0.67945 0.3048)
			(end 0.67945 -0.305054)
			(stroke
				(width 0.1)
				(type default)
			)
			(layer "B.Fab")
		)
		(fp_line
			(start -0.120396 0.2794)
			(end 0.12065 0.2794)
			(stroke
				(width 0.1)
				(type default)
			)
			(layer "B.Fab")
		)
		(fp_line
			(start 0.12065 0.2794)
			(end 0.12065 0.3048)
			(stroke
				(width 0.1)
				(type default)
			)
			(layer "B.Fab")
		)
		(fp_line
			(start -0.12065 -0.2794)
			(end -0.12065 -0.3048)
			(stroke
				(width 0.1)
				(type default)
			)
			(layer "B.Fab")
		)
		(fp_line
			(start 0.12065 -0.2794)
			(end -0.12065 -0.2794)
			(stroke
				(width 0.1)
				(type default)
			)
			(layer "B.Fab")
		)
		(fp_line
			(start -0.67945 -0.3048)
			(end -0.67945 0.3048)
			(stroke
				(width 0.1)
				(type default)
			)
			(layer "B.Fab")
		)
		(fp_line
			(start -0.12065 -0.3048)
			(end -0.67945 -0.3048)
			(stroke
				(width 0.1)
				(type default)
			)
			(layer "B.Fab")
		)
		(fp_line
			(start 0.12065 -0.305054)
			(end 0.12065 -0.2794)
			(stroke
				(width 0.1)
				(type default)
			)
			(layer "B.Fab")
		)
		(fp_line
			(start 0.67945 -0.305054)
			(end 0.12065 -0.305054)
			(stroke
				(width 0.1)
				(type default)
			)
			(layer "B.Fab")
		)
		(pad "1" smd circle
			(at 0.40005 0 90)
			(size 0 0)
			(layers "B.Cu" "B.Mask" "B.Paste")
			(net "P3V3_CLK_BUFFER_9ZXL0451E_S3_VZX3P3")
		)
		(pad "2" smd circle
			(at -0.40005 0 90)
			(size 0 0)
			(layers "B.Cu" "B.Mask" "B.Paste")
			(net "GND")
		)
	)
	(footprint ""
		(layer "B.Cu")
		(at 176.699926 -299.699934 -90)
		(property "Reference" "C1492"
			(at 0 0 90)
			(layer "B.SilkS")
			(hide yes)
			(effects
				(font
					(size 1.27 1.27)
				)
				(justify mirror)
			)
		)
		(property "Value" ""
			(at 0 0 90)
			(layer "B.Fab")
			(effects
				(font
					(size 1.27 1.27)
				)
				(justify mirror)
			)
		)
		(duplicate_pad_numbers_are_jumpers no)
		(fp_line
			(start -0.299974 0.150114)
			(end 0.299974 0.150114)
			(stroke
				(width 0.1)
				(type default)
			)
			(layer "B.Fab")
		)
		(fp_line
			(start 0.299974 0.150114)
			(end 0.299974 -0.150114)
			(stroke
				(width 0.1)
				(type default)
			)
			(layer "B.Fab")
		)
		(fp_line
			(start -0.299974 -0.150114)
			(end -0.299974 0.150114)
			(stroke
				(width 0.1)
				(type default)
			)
			(layer "B.Fab")
		)
		(fp_line
			(start 0.299974 -0.150114)
			(end -0.299974 -0.150114)
			(stroke
				(width 0.1)
				(type default)
			)
			(layer "B.Fab")
		)
		(pad "1" smd rect
			(at 0.2667 0 90)
			(size 0.3048 0.381)
			(layers "B.Cu" "B.Mask" "B.Paste")
			(net "P0V8_SERDES_VDDA_PEX1")
		)
		(pad "2" smd rect
			(at -0.2667 0 90)
			(size 0.3048 0.381)
			(layers "B.Cu" "B.Mask" "B.Paste")
			(net "GND")
		)
	)
	(footprint ""
		(layer "B.Cu")
		(at 298.499784 -301.599854 -90)
		(property "Reference" "C1692"
			(at 0 0 90)
			(layer "B.SilkS")
			(hide yes)
			(effects
				(font
					(size 1.27 1.27)
				)
				(justify mirror)
			)
		)
		(property "Value" ""
			(at 0 0 90)
			(layer "B.Fab")
			(effects
				(font
					(size 1.27 1.27)
				)
				(justify mirror)
			)
		)
		(duplicate_pad_numbers_are_jumpers no)
		(fp_line
			(start -0.299974 0.150114)
			(end 0.299974 0.150114)
			(stroke
				(width 0.1)
				(type default)
			)
			(layer "B.Fab")
		)
		(fp_line
			(start 0.299974 0.150114)
			(end 0.299974 -0.150114)
			(stroke
				(width 0.1)
				(type default)
			)
			(layer "B.Fab")
		)
		(fp_line
			(start -0.299974 -0.150114)
			(end -0.299974 0.150114)
			(stroke
				(width 0.1)
				(type default)
			)
			(layer "B.Fab")
		)
		(fp_line
			(start 0.299974 -0.150114)
			(end -0.299974 -0.150114)
			(stroke
				(width 0.1)
				(type default)
			)
			(layer "B.Fab")
		)
		(pad "1" smd rect
			(at 0.2667 0 90)
			(size 0.3048 0.381)
			(layers "B.Cu" "B.Mask" "B.Paste")
			(net "P0V8_SERDES_VDDA_PEX2")
		)
		(pad "2" smd rect
			(at -0.2667 0 90)
			(size 0.3048 0.381)
			(layers "B.Cu" "B.Mask" "B.Paste")
			(net "GND")
		)
	)
	(footprint ""
		(layer "B.Cu")
		(at 287.574736 -297.79976 90)
		(property "Reference" "C1664"
			(at 0 0 90)
			(layer "B.SilkS")
			(hide yes)
			(effects
				(font
					(size 1.27 1.27)
				)
				(justify mirror)
			)
		)
		(property "Value" ""
			(at 0 0 90)
			(layer "B.Fab")
			(effects
				(font
					(size 1.27 1.27)
				)
				(justify mirror)
			)
		)
		(duplicate_pad_numbers_are_jumpers no)
		(fp_line
			(start 0.299974 -0.150114)
			(end -0.299974 -0.150114)
			(stroke
				(width 0.1)
				(type default)
			)
			(layer "B.Fab")
		)
		(fp_line
			(start -0.299974 -0.150114)
			(end -0.299974 0.150114)
			(stroke
				(width 0.1)
				(type default)
			)
			(layer "B.Fab")
		)
		(fp_line
			(start 0.299974 0.150114)
			(end 0.299974 -0.150114)
			(stroke
				(width 0.1)
				(type default)
			)
			(layer "B.Fab")
		)
		(fp_line
			(start -0.299974 0.150114)
			(end 0.299974 0.150114)
			(stroke
				(width 0.1)
				(type default)
			)
			(layer "B.Fab")
		)
		(pad "1" smd rect
			(at 0.2667 0 270)
			(size 0.3048 0.381)
			(layers "B.Cu" "B.Mask" "B.Paste")
			(net "P0V8_PEX2")
		)
		(pad "2" smd rect
			(at -0.2667 0 270)
			(size 0.3048 0.381)
			(layers "B.Cu" "B.Mask" "B.Paste")
			(net "GND")
		)
	)
	(footprint ""
		(layer "B.Cu")
		(at 337.488022 -319.420494 -90)
		(property "Reference" "R5793"
			(at 0 0 90)
			(layer "B.SilkS")
			(hide yes)
			(effects
				(font
					(size 1.27 1.27)
				)
				(justify mirror)
			)
		)
		(property "Value" ""
			(at 0 0 90)
			(layer "B.Fab")
			(effects
				(font
					(size 1.27 1.27)
				)
				(justify mirror)
			)
		)
		(duplicate_pad_numbers_are_jumpers no)
		(fp_line
			(start -2.576322 1.1303)
			(end 2.576322 1.1303)
			(stroke
				(width 0.1524)
				(type default)
			)
			(layer "B.SilkS")
		)
		(fp_line
			(start 2.576322 1.1303)
			(end 2.576322 -1.1303)
			(stroke
				(width 0.1524)
				(type default)
			)
			(layer "B.SilkS")
		)
		(fp_line
			(start -2.576322 -1.1303)
			(end -2.576322 1.1303)
			(stroke
				(width 0.1524)
				(type default)
			)
			(layer "B.SilkS")
		)
		(fp_line
			(start 2.576322 -1.1303)
			(end -2.576322 -1.1303)
			(stroke
				(width 0.1524)
				(type default)
			)
			(layer "B.SilkS")
		)
		(fp_line
			(start -1.649984 0.899922)
			(end -1.649984 -0.899922)
			(stroke
				(width 0.1)
				(type default)
			)
			(layer "B.Fab")
		)
		(fp_line
			(start 1.649984 0.899922)
			(end -1.649984 0.899922)
			(stroke
				(width 0.1)
				(type default)
			)
			(layer "B.Fab")
		)
		(fp_line
			(start -1.649984 -0.899922)
			(end 1.649984 -0.899922)
			(stroke
				(width 0.1)
				(type default)
			)
			(layer "B.Fab")
		)
		(fp_line
			(start 1.649984 -0.899922)
			(end 1.649984 0.899922)
			(stroke
				(width 0.1)
				(type default)
			)
			(layer "B.Fab")
		)
		(pad "1A" smd rect
			(at 1.700022 0 90)
			(size 1.4986 2.0066)
			(layers "B.Cu" "B.Mask" "B.Paste")
			(net "P0V8_PEX2")
		)
		(pad "1B" smd rect
			(at 1.077722 0 90)
			(size 0.254 0.508)
			(layers "B.Cu" "B.Mask" "B.Paste")
			(net "P0V8_PEX2")
		)
		(pad "2A" smd rect
			(at -1.700022 0 90)
			(size 1.4986 2.0066)
			(layers "B.Cu" "B.Mask" "B.Paste")
			(net "P0V8_SERDES_VDDA_PEX2")
		)
		(pad "2B" smd rect
			(at -1.077722 0 90)
			(size 0.254 0.508)
			(layers "B.Cu" "B.Mask" "B.Paste")
			(net "P0V8_SERDES_VDDA_PEX2")
		)
	)
)
